(kicad_pcb
	(version 20260206)
	(generator "pcbnew")
	(generator_version "10.0")
	(general
		(thickness 1.6)
		(legacy_teardrops no)
	)
	(paper "A4")
	(title_block
		(title "v1-chassis-manager — T6M_CM_d_v01_1031_1645.brd")
		(comment 1 "Open CloudServer (Microsoft) / footprints 1776-1785 of 2512")
	)
	(layers
		(0 "F.Cu" signal "TOP")
		(4 "In1.Cu" signal "GND1")
		(6 "In2.Cu" signal "IN1")
		(8 "In3.Cu" signal "VCC1")
		(10 "In4.Cu" signal "VCC2")
		(12 "In5.Cu" signal "GND2")
		(14 "In6.Cu" signal "IN2")
		(16 "In7.Cu" signal "IN3")
		(18 "In8.Cu" signal "GND3")
		(2 "B.Cu" signal "BOTTOM")
		(9 "F.Adhes" user "F.Adhesive")
		(11 "B.Adhes" user "B.Adhesive")
		(13 "F.Paste" user "Package Geometry/Pastemask Top")
		(15 "B.Paste" user "Package Geometry/Pastemask Bottom")
		(5 "F.SilkS" user "Ref Des/Silkscreen Top")
		(7 "B.SilkS" user "Ref Des/Silkscreen Bottom")
		(1 "F.Mask" user "Board Geometry/Soldermask Top")
		(3 "B.Mask" user "Board Geometry/Soldermask Bottom")
		(17 "Dwgs.User" user "User.Drawings")
		(19 "Cmts.User" user "User.Comments")
		(21 "Eco1.User" user "User.Eco1")
		(23 "Eco2.User" user "User.Eco2")
		(25 "Edge.Cuts" user "Board Geometry/Outline")
		(27 "Margin" user)
		(31 "F.CrtYd" user "Package Geometry/Place Bound Top")
		(29 "B.CrtYd" user "Package Geometry/Place Bound Bottom")
		(35 "F.Fab" user "Ref Des/Assembly Top")
		(33 "B.Fab" user "Ref Des/Assembly Bottom")
	)
	(footprint ""
		(layer "B.Cu")
		(at 54.215538 -72.292718 180)
		(property "Reference" "C125"
			(at 12.404598 -31.464758 0)
			(unlocked yes)
			(layer "B.SilkS")
			(effects
				(font
					(size 0.7874 0.5842)
					(thickness 0.1524)
				)
				(justify left mirror)
			)
		)
		(property "Value" ""
			(at 0 0 0)
			(layer "B.Fab")
			(effects
				(font
					(size 1.27 1.27)
				)
				(justify mirror)
			)
		)
		(duplicate_pad_numbers_are_jumpers no)
		(fp_line
			(start 0.7874 0.4064)
			(end 0.7874 -0.4064)
			(stroke
				(width 0.1524)
				(type default)
			)
			(layer "B.SilkS")
		)
		(fp_line
			(start 0.7874 -0.4064)
			(end -0.7874 -0.4064)
			(stroke
				(width 0.1524)
				(type default)
			)
			(layer "B.SilkS")
		)
		(fp_line
			(start 0 0.381)
			(end 0 -0.381)
			(stroke
				(width 0.1524)
				(type default)
			)
			(layer "B.SilkS")
		)
		(fp_line
			(start -0.7874 0.4064)
			(end 0.7874 0.4064)
			(stroke
				(width 0.1524)
				(type default)
			)
			(layer "B.SilkS")
		)
		(fp_line
			(start -0.7874 -0.4064)
			(end -0.7874 0.4064)
			(stroke
				(width 0.1524)
				(type default)
			)
			(layer "B.SilkS")
		)
		(fp_poly
			(pts
				(xy 0.5334 0.254) (xy 0.635 0.254) (xy 0.635 0.2286) (xy 0.635 -0.254) (xy 0.5334 -0.254) (xy 0.5334 -0.2794)
				(xy -0.5334 -0.2794) (xy -0.5334 -0.254) (xy -0.635 -0.254) (xy -0.635 0.254) (xy -0.5334 0.254)
				(xy -0.5334 0.2794) (xy 0.508 0.2794) (xy 0.5334 0.2794)
			)
			(stroke
				(width 0)
				(type default)
			)
			(fill no)
			(layer "B.CrtYd")
		)
		(pad "1" smd rect
			(at -0.40005 0)
			(size 0.4572 0.508)
			(layers "B.Cu" "B.Mask" "B.Paste")
			(net "P1V05_NODE1")
		)
		(pad "2" smd rect
			(at 0.40005 0)
			(size 0.4572 0.508)
			(layers "B.Cu" "B.Mask" "B.Paste")
			(net "GND")
		)
	)
	(footprint ""
		(layer "B.Cu")
		(at 160.816798 -157.77083 -90)
		(property "Reference" "C440"
			(at -2.361184 0.790702 270)
			(unlocked yes)
			(layer "B.SilkS")
			(effects
				(font
					(size 0.7874 0.5842)
					(thickness 0.1524)
				)
				(justify left mirror)
			)
		)
		(property "Value" ""
			(at 0 0 90)
			(layer "B.Fab")
			(effects
				(font
					(size 1.27 1.27)
				)
				(justify mirror)
			)
		)
		(duplicate_pad_numbers_are_jumpers no)
		(fp_line
			(start -0.7874 0.4064)
			(end 0.7874 0.4064)
			(stroke
				(width 0.1524)
				(type default)
			)
			(layer "B.SilkS")
		)
		(fp_line
			(start 0.7874 0.4064)
			(end 0.7874 -0.4064)
			(stroke
				(width 0.1524)
				(type default)
			)
			(layer "B.SilkS")
		)
		(fp_line
			(start 0 0.381)
			(end 0 -0.381)
			(stroke
				(width 0.1524)
				(type default)
			)
			(layer "B.SilkS")
		)
		(fp_line
			(start -0.7874 -0.4064)
			(end -0.7874 0.4064)
			(stroke
				(width 0.1524)
				(type default)
			)
			(layer "B.SilkS")
		)
		(fp_line
			(start 0.7874 -0.4064)
			(end -0.7874 -0.4064)
			(stroke
				(width 0.1524)
				(type default)
			)
			(layer "B.SilkS")
		)
		(fp_poly
			(pts
				(xy 0.5334 0.254) (xy 0.635 0.254) (xy 0.635 0.2286) (xy 0.635 -0.254) (xy 0.5334 -0.254) (xy 0.5334 -0.2794)
				(xy -0.5334 -0.2794) (xy -0.5334 -0.254) (xy -0.635 -0.254) (xy -0.635 0.254) (xy -0.5334 0.254)
				(xy -0.5334 0.2794) (xy 0.508 0.2794) (xy 0.5334 0.2794)
			)
			(stroke
				(width 0)
				(type default)
			)
			(fill no)
			(layer "B.CrtYd")
		)
		(pad "1" smd rect
			(at -0.40005 0 90)
			(size 0.4572 0.508)
			(layers "B.Cu" "B.Mask" "B.Paste")
			(net "P3V3_NODE1")
		)
		(pad "2" smd rect
			(at 0.40005 0 90)
			(size 0.4572 0.508)
			(layers "B.Cu" "B.Mask" "B.Paste")
			(net "GND")
		)
	)
	(footprint ""
		(layer "B.Cu")
		(at 131.93776 -187.872624 -90)
		(property "Reference" "C728"
			(at -4.565396 1.17475 270)
			(unlocked yes)
			(layer "B.SilkS")
			(effects
				(font
					(size 0.7874 0.5842)
					(thickness 0.1524)
				)
				(justify left mirror)
			)
		)
		(property "Value" ""
			(at 0 0 90)
			(layer "B.Fab")
			(effects
				(font
					(size 1.27 1.27)
				)
				(justify mirror)
			)
		)
		(duplicate_pad_numbers_are_jumpers no)
		(fp_line
			(start -0.7874 0.4064)
			(end 0.7874 0.4064)
			(stroke
				(width 0.1524)
				(type default)
			)
			(layer "B.SilkS")
		)
		(fp_line
			(start 0.7874 0.4064)
			(end 0.7874 -0.4064)
			(stroke
				(width 0.1524)
				(type default)
			)
			(layer "B.SilkS")
		)
		(fp_line
			(start 0 0.381)
			(end 0 -0.381)
			(stroke
				(width 0.1524)
				(type default)
			)
			(layer "B.SilkS")
		)
		(fp_line
			(start -0.7874 -0.4064)
			(end -0.7874 0.4064)
			(stroke
				(width 0.1524)
				(type default)
			)
			(layer "B.SilkS")
		)
		(fp_line
			(start 0.7874 -0.4064)
			(end -0.7874 -0.4064)
			(stroke
				(width 0.1524)
				(type default)
			)
			(layer "B.SilkS")
		)
		(fp_poly
			(pts
				(xy 0.5334 0.254) (xy 0.635 0.254) (xy 0.635 0.2286) (xy 0.635 -0.254) (xy 0.5334 -0.254) (xy 0.5334 -0.2794)
				(xy -0.5334 -0.2794) (xy -0.5334 -0.254) (xy -0.635 -0.254) (xy -0.635 0.254) (xy -0.5334 0.254)
				(xy -0.5334 0.2794) (xy 0.508 0.2794) (xy 0.5334 0.2794)
			)
			(stroke
				(width 0)
				(type default)
			)
			(fill no)
			(layer "B.CrtYd")
		)
		(pad "1" smd rect
			(at -0.40005 0 90)
			(size 0.4572 0.508)
			(layers "B.Cu" "B.Mask" "B.Paste")
			(net "UART_T9_NODE2_TXD_R")
		)
		(pad "2" smd rect
			(at 0.40005 0 90)
			(size 0.4572 0.508)
			(layers "B.Cu" "B.Mask" "B.Paste")
			(net "GND")
		)
	)
	(footprint ""
		(layer "B.Cu")
		(at 39.638732 -94.40037 90)
		(property "Reference" "R130"
			(at -4.703318 -4.648454 270)
			(unlocked yes)
			(layer "B.SilkS")
			(effects
				(font
					(size 0.7874 0.5842)
					(thickness 0.1524)
				)
				(justify left mirror)
			)
		)
		(property "Value" ""
			(at 0 0 90)
			(layer "B.Fab")
			(effects
				(font
					(size 1.27 1.27)
				)
				(justify mirror)
			)
		)
		(duplicate_pad_numbers_are_jumpers no)
		(fp_line
			(start 0.7874 -0.4064)
			(end -0.7874 -0.4064)
			(stroke
				(width 0.1524)
				(type default)
			)
			(layer "B.SilkS")
		)
		(fp_line
			(start -0.7874 -0.4064)
			(end -0.7874 0.4064)
			(stroke
				(width 0.1524)
				(type default)
			)
			(layer "B.SilkS")
		)
		(fp_line
			(start 0.7874 0.4064)
			(end 0.7874 -0.4064)
			(stroke
				(width 0.1524)
				(type default)
			)
			(layer "B.SilkS")
		)
		(fp_line
			(start -0.7874 0.4064)
			(end 0.7874 0.4064)
			(stroke
				(width 0.1524)
				(type default)
			)
			(layer "B.SilkS")
		)
		(fp_poly
			(pts
				(xy 0.508 0.2794) (xy 0.508 0.2286) (xy 0.635 0.2286) (xy 0.635 -0.254) (xy 0.5334 -0.254) (xy 0.5334 -0.2794)
				(xy -0.5334 -0.2794) (xy -0.5334 -0.254) (xy -0.635 -0.254) (xy -0.635 0.254) (xy -0.5334 0.254)
				(xy -0.5334 0.2794)
			)
			(stroke
				(width 0)
				(type default)
			)
			(fill no)
			(layer "B.CrtYd")
		)
		(pad "1" smd rect
			(at -0.40005 0 270)
			(size 0.4572 0.508)
			(layers "B.Cu" "B.Mask" "B.Paste")
			(net "SMB_CPU_NODE1_BMC_CLK_RR")
		)
		(pad "2" smd rect
			(at 0.40005 0 270)
			(size 0.4572 0.508)
			(layers "B.Cu" "B.Mask" "B.Paste")
			(net "SMB_CPU_NODE1_BMC_CLK")
		)
	)
	(footprint ""
		(layer "B.Cu")
		(at 128.889252 -142.85595 180)
		(property "Reference" "L53"
			(at -3.670808 0.096266 0)
			(unlocked yes)
			(layer "B.SilkS")
			(effects
				(font
					(size 0.7874 0.5842)
					(thickness 0.1524)
				)
				(justify mirror)
			)
		)
		(property "Value" ""
			(at 0 0 0)
			(layer "B.Fab")
			(effects
				(font
					(size 1.27 1.27)
				)
				(justify mirror)
			)
		)
		(duplicate_pad_numbers_are_jumpers no)
		(fp_line
			(start 1.2954 -0.635)
			(end 1.2954 0.635)
			(stroke
				(width 0.1524)
				(type default)
			)
			(layer "B.SilkS")
		)
		(fp_line
			(start 1.2954 -0.635)
			(end -1.2954 -0.635)
			(stroke
				(width 0.1524)
				(type default)
			)
			(layer "B.SilkS")
		)
		(fp_line
			(start 0.127 -0.5842)
			(end 0.127 0.5842)
			(stroke
				(width 0.1524)
				(type default)
			)
			(layer "B.SilkS")
		)
		(fp_line
			(start -0.127 -0.5842)
			(end -0.127 0.5842)
			(stroke
				(width 0.1524)
				(type default)
			)
			(layer "B.SilkS")
		)
		(fp_line
			(start -1.2954 0.635)
			(end 1.2954 0.635)
			(stroke
				(width 0.1524)
				(type default)
			)
			(layer "B.SilkS")
		)
		(fp_line
			(start -1.2954 -0.635)
			(end -1.2954 0.635)
			(stroke
				(width 0.1524)
				(type default)
			)
			(layer "B.SilkS")
		)
		(fp_poly
			(pts
				(xy 0.9144 0.508) (xy 0.9144 0.3556) (xy 1.143 0.3556) (xy 1.143 -0.3556) (xy 0.9144 -0.3556) (xy 0.9144 -0.508)
				(xy -0.9144 -0.508) (xy -0.9144 -0.3556) (xy -1.143 -0.3556) (xy -1.143 0.3556) (xy -0.9144 0.3556)
				(xy -0.9144 0.508)
			)
			(stroke
				(width 0)
				(type default)
			)
			(fill no)
			(layer "B.CrtYd")
		)
		(pad "1" smd rect
			(at -0.7366 0 270)
			(size 0.7112 0.8128)
			(layers "B.Cu" "B.Mask" "B.Paste")
			(net "P1V0_NODE1")
		)
		(pad "2" smd rect
			(at 0.7366 0 270)
			(size 0.7112 0.8128)
			(layers "B.Cu" "B.Mask" "B.Paste")
			(net "P1V0_PCI_SW_A")
		)
	)
	(footprint ""
		(layer "B.Cu")
		(at 44.91482 -159.16529 -90)
		(property "Reference" "C418"
			(at -7.05485 6.84276 270)
			(unlocked yes)
			(layer "B.SilkS")
			(effects
				(font
					(size 0.7874 0.5842)
					(thickness 0.1524)
				)
				(justify left mirror)
			)
		)
		(property "Value" ""
			(at 0 0 90)
			(layer "B.Fab")
			(effects
				(font
					(size 1.27 1.27)
				)
				(justify mirror)
			)
		)
		(duplicate_pad_numbers_are_jumpers no)
		(fp_line
			(start -0.7874 0.4064)
			(end 0.7874 0.4064)
			(stroke
				(width 0.1524)
				(type default)
			)
			(layer "B.SilkS")
		)
		(fp_line
			(start 0.7874 0.4064)
			(end 0.7874 -0.4064)
			(stroke
				(width 0.1524)
				(type default)
			)
			(layer "B.SilkS")
		)
		(fp_line
			(start 0 0.381)
			(end 0 -0.381)
			(stroke
				(width 0.1524)
				(type default)
			)
			(layer "B.SilkS")
		)
		(fp_line
			(start -0.7874 -0.4064)
			(end -0.7874 0.4064)
			(stroke
				(width 0.1524)
				(type default)
			)
			(layer "B.SilkS")
		)
		(fp_line
			(start 0.7874 -0.4064)
			(end -0.7874 -0.4064)
			(stroke
				(width 0.1524)
				(type default)
			)
			(layer "B.SilkS")
		)
		(fp_poly
			(pts
				(xy 0.5334 0.254) (xy 0.635 0.254) (xy 0.635 0.2286) (xy 0.635 -0.254) (xy 0.5334 -0.254) (xy 0.5334 -0.2794)
				(xy -0.5334 -0.2794) (xy -0.5334 -0.254) (xy -0.635 -0.254) (xy -0.635 0.254) (xy -0.5334 0.254)
				(xy -0.5334 0.2794) (xy 0.508 0.2794) (xy 0.5334 0.2794)
			)
			(stroke
				(width 0)
				(type default)
			)
			(fill no)
			(layer "B.CrtYd")
		)
		(pad "1" smd rect
			(at -0.40005 0 90)
			(size 0.4572 0.508)
			(layers "B.Cu" "B.Mask" "B.Paste")
			(net "P1V05_LAN1")
		)
		(pad "2" smd rect
			(at 0.40005 0 90)
			(size 0.4572 0.508)
			(layers "B.Cu" "B.Mask" "B.Paste")
			(net "GND")
		)
	)
	(footprint ""
		(layer "B.Cu")
		(at 152.588214 -62.075822 90)
		(property "Reference" "C357"
			(at -2.829814 6.128512 270)
			(unlocked yes)
			(layer "B.SilkS")
			(effects
				(font
					(size 0.7874 0.5842)
					(thickness 0.1524)
				)
				(justify left mirror)
			)
		)
		(property "Value" ""
			(at 0 0 90)
			(layer "B.Fab")
			(effects
				(font
					(size 1.27 1.27)
				)
				(justify mirror)
			)
		)
		(duplicate_pad_numbers_are_jumpers no)
		(fp_line
			(start 0.7874 -0.4064)
			(end -0.7874 -0.4064)
			(stroke
				(width 0.1524)
				(type default)
			)
			(layer "B.SilkS")
		)
		(fp_line
			(start -0.7874 -0.4064)
			(end -0.7874 0.4064)
			(stroke
				(width 0.1524)
				(type default)
			)
			(layer "B.SilkS")
		)
		(fp_line
			(start 0 0.381)
			(end 0 -0.381)
			(stroke
				(width 0.1524)
				(type default)
			)
			(layer "B.SilkS")
		)
		(fp_line
			(start 0.7874 0.4064)
			(end 0.7874 -0.4064)
			(stroke
				(width 0.1524)
				(type default)
			)
			(layer "B.SilkS")
		)
		(fp_line
			(start -0.7874 0.4064)
			(end 0.7874 0.4064)
			(stroke
				(width 0.1524)
				(type default)
			)
			(layer "B.SilkS")
		)
		(fp_poly
			(pts
				(xy 0.5334 0.254) (xy 0.635 0.254) (xy 0.635 0.2286) (xy 0.635 -0.254) (xy 0.5334 -0.254) (xy 0.5334 -0.2794)
				(xy -0.5334 -0.2794) (xy -0.5334 -0.254) (xy -0.635 -0.254) (xy -0.635 0.254) (xy -0.5334 0.254)
				(xy -0.5334 0.2794) (xy 0.508 0.2794) (xy 0.5334 0.2794)
			)
			(stroke
				(width 0)
				(type default)
			)
			(fill no)
			(layer "B.CrtYd")
		)
		(pad "1" smd rect
			(at -0.40005 0 270)
			(size 0.4572 0.508)
			(layers "B.Cu" "B.Mask" "B.Paste")
			(net "GND")
		)
		(pad "2" smd rect
			(at 0.40005 0 270)
			(size 0.4572 0.508)
			(layers "B.Cu" "B.Mask" "B.Paste")
			(net "P1V8_SATA_VAA2_1_NODE1")
		)
	)
	(footprint ""
		(layer "B.Cu")
		(at 55.935372 -68.475098 -90)
		(property "Reference" "C93"
			(at 32.281622 14.138402 270)
			(unlocked yes)
			(layer "B.SilkS")
			(effects
				(font
					(size 0.7874 0.5842)
					(thickness 0.1524)
				)
				(justify mirror)
			)
		)
		(property "Value" ""
			(at 0 0 90)
			(layer "B.Fab")
			(effects
				(font
					(size 1.27 1.27)
				)
				(justify mirror)
			)
		)
		(duplicate_pad_numbers_are_jumpers no)
		(fp_line
			(start -1.2954 0.5842)
			(end 1.2954 0.5842)
			(stroke
				(width 0.1524)
				(type default)
			)
			(layer "B.SilkS")
		)
		(fp_line
			(start 1.2954 0.5842)
			(end 1.2954 -0.5842)
			(stroke
				(width 0.1524)
				(type default)
			)
			(layer "B.SilkS")
		)
		(fp_line
			(start -1.2954 -0.5842)
			(end -1.2954 0.5842)
			(stroke
				(width 0.1524)
				(type default)
			)
			(layer "B.SilkS")
		)
		(fp_line
			(start 0 -0.5842)
			(end 0 0.5842)
			(stroke
				(width 0.1524)
				(type default)
			)
			(layer "B.SilkS")
		)
		(fp_line
			(start 1.2954 -0.5842)
			(end -1.2954 -0.5842)
			(stroke
				(width 0.1524)
				(type default)
			)
			(layer "B.SilkS")
		)
		(fp_poly
			(pts
				(xy -0.8636 -0.4572) (xy -0.8636 -0.3556) (xy -1.143 -0.3556) (xy -1.143 0.3556) (xy -0.8636 0.3556)
				(xy -0.8636 0.4572) (xy 0.8636 0.4572) (xy 0.8636 0.3556) (xy 1.143 0.3556) (xy 1.143 -0.3556) (xy 0.8636 -0.3556)
				(xy 0.8636 -0.4572)
			)
			(stroke
				(width 0)
				(type default)
			)
			(fill no)
			(layer "B.CrtYd")
		)
		(fp_line
			(start -0.884936 0.504952)
			(end 0.884936 0.504952)
			(stroke
				(width 0.1)
				(type default)
			)
			(layer "B.Fab")
		)
		(fp_line
			(start 0.884936 0.504952)
			(end 0.884936 -0.504952)
			(stroke
				(width 0.1)
				(type default)
			)
			(layer "B.Fab")
		)
		(fp_line
			(start -0.884936 -0.504952)
			(end -0.884936 0.504952)
			(stroke
				(width 0.1)
				(type default)
			)
			(layer "B.Fab")
		)
		(fp_line
			(start 0.884936 -0.504952)
			(end -0.884936 -0.504952)
			(stroke
				(width 0.1)
				(type default)
			)
			(layer "B.Fab")
		)
		(pad "1" smd rect
			(at -0.7366 0)
			(size 0.7112 0.8128)
			(layers "B.Cu" "B.Mask" "B.Paste")
			(net "P1V5_SFRPLL_NODE1")
		)
		(pad "2" smd rect
			(at 0.7366 0)
			(size 0.7112 0.8128)
			(layers "B.Cu" "B.Mask" "B.Paste")
			(net "GND")
		)
	)
	(footprint ""
		(layer "B.Cu")
		(at 72.178672 -139.190222)
		(property "Reference" "TP7"
			(at 0 0 0)
			(layer "B.SilkS")
			(hide yes)
			(effects
				(font
					(size 1.27 1.27)
				)
				(justify mirror)
			)
		)
		(property "Value" ""
			(at 0 0 0)
			(layer "B.Fab")
			(effects
				(font
					(size 1.27 1.27)
				)
				(justify mirror)
			)
		)
		(duplicate_pad_numbers_are_jumpers no)
		(fp_poly
			(pts
				(arc
					(start 0 -0.381)
					(mid 0 0.381)
					(end 0 -0.381)
				)
			)
			(stroke
				(width 0)
				(type default)
			)
			(fill no)
			(layer "B.CrtYd")
		)
		(pad "1" smd circle
			(at 0 0 180)
			(size 0.762 0.762)
			(layers "B.Cu" "B.Mask" "B.Paste")
			(net "N3975090767")
		)
	)
	(footprint ""
		(layer "B.Cu")
		(at 177.967386 -120.774968 180)
		(property "Reference" "C788"
			(at -10.430764 -0.49022 0)
			(unlocked yes)
			(layer "B.SilkS")
			(effects
				(font
					(size 0.7874 0.5842)
					(thickness 0.1524)
				)
				(justify mirror)
			)
		)
		(property "Value" ""
			(at 0 0 0)
			(layer "B.Fab")
			(effects
				(font
					(size 1.27 1.27)
				)
				(justify mirror)
			)
		)
		(duplicate_pad_numbers_are_jumpers no)
		(fp_line
			(start 1.2954 0.5842)
			(end 1.2954 -0.5842)
			(stroke
				(width 0.1524)
				(type default)
			)
			(layer "B.SilkS")
		)
		(fp_line
			(start 1.2954 -0.5842)
			(end -1.2954 -0.5842)
			(stroke
				(width 0.1524)
				(type default)
			)
			(layer "B.SilkS")
		)
		(fp_line
			(start 0 -0.5842)
			(end 0 0.5842)
			(stroke
				(width 0.1524)
				(type default)
			)
			(layer "B.SilkS")
		)
		(fp_line
			(start -1.2954 0.5842)
			(end 1.2954 0.5842)
			(stroke
				(width 0.1524)
				(type default)
			)
			(layer "B.SilkS")
		)
		(fp_line
			(start -1.2954 -0.5842)
			(end -1.2954 0.5842)
			(stroke
				(width 0.1524)
				(type default)
			)
			(layer "B.SilkS")
		)
		(fp_poly
			(pts
				(xy -0.8636 -0.4572) (xy -0.8636 -0.3556) (xy -1.143 -0.3556) (xy -1.143 0.3556) (xy -0.8636 0.3556)
				(xy -0.8636 0.4572) (xy 0.8636 0.4572) (xy 0.8636 0.3556) (xy 1.143 0.3556) (xy 1.143 -0.3556) (xy 0.8636 -0.3556)
				(xy 0.8636 -0.4572)
			)
			(stroke
				(width 0)
				(type default)
			)
			(fill no)
			(layer "B.CrtYd")
		)
		(fp_line
			(start 0.884936 0.504952)
			(end 0.884936 -0.504952)
			(stroke
				(width 0.1)
				(type default)
			)
			(layer "B.Fab")
		)
		(fp_line
			(start 0.884936 -0.504952)
			(end -0.884936 -0.504952)
			(stroke
				(width 0.1)
				(type default)
			)
			(layer "B.Fab")
		)
		(fp_line
			(start -0.884936 0.504952)
			(end 0.884936 0.504952)
			(stroke
				(width 0.1)
				(type default)
			)
			(layer "B.Fab")
		)
		(fp_line
			(start -0.884936 -0.504952)
			(end -0.884936 0.504952)
			(stroke
				(width 0.1)
				(type default)
			)
			(layer "B.Fab")
		)
		(pad "1" smd rect
			(at -0.7366 0 270)
			(size 0.7112 0.8128)
			(layers "B.Cu" "B.Mask" "B.Paste")
			(net "P3V3_STB_NODE1")
		)
		(pad "2" smd rect
			(at 0.7366 0 270)
			(size 0.7112 0.8128)
			(layers "B.Cu" "B.Mask" "B.Paste")
			(net "GND")
		)
	)
)
